(kicad_pcb
	(version 20260206)
	(generator "pcbnew")
	(generator_version "10.0")
	(general
		(thickness 1.6)
		(legacy_teardrops no)
	)
	(paper "A4")
	(title_block
		(title "panther-plus-userver — 13130-1b_20150205.brd")
		(comment 1 "Honey Badger (Wiwynn) / footprints 246-253 of 1509")
	)
	(layers
		(0 "F.Cu" signal "TOP")
		(4 "In1.Cu" signal "L2")
		(6 "In2.Cu" signal "L3")
		(8 "In3.Cu" signal "L4")
		(10 "In4.Cu" signal "L5")
		(12 "In5.Cu" signal "L6")
		(14 "In6.Cu" signal "L7")
		(16 "In7.Cu" signal "L8")
		(18 "In8.Cu" signal "L9")
		(20 "In9.Cu" signal "L10")
		(22 "In10.Cu" signal "L11")
		(2 "B.Cu" signal "BOTTOM")
		(9 "F.Adhes" user "F.Adhesive")
		(11 "B.Adhes" user "B.Adhesive")
		(13 "F.Paste" user "Package Geometry/Pastemask Top")
		(15 "B.Paste" user "Package Geometry/Pastemask Bottom")
		(5 "F.SilkS" user "Ref Des/Silkscreen Top")
		(7 "B.SilkS" user "Ref Des/Silkscreen Bottom")
		(1 "F.Mask" user "Board Geometry/Soldermask Top")
		(3 "B.Mask" user "Board Geometry/Soldermask Bottom")
		(17 "Dwgs.User" user "User.Drawings")
		(19 "Cmts.User" user "User.Comments")
		(21 "Eco1.User" user "User.Eco1")
		(23 "Eco2.User" user "User.Eco2")
		(25 "Edge.Cuts" user "Board Geometry/Outline")
		(27 "Margin" user)
		(31 "F.CrtYd" user "Package Geometry/Place Bound Top")
		(29 "B.CrtYd" user "Package Geometry/Place Bound Bottom")
		(35 "F.Fab" user "Ref Des/Assembly Top")
		(33 "B.Fab" user "Ref Des/Assembly Bottom")
	)
	(footprint ""
		(layer "F.Cu")
		(at 11.557 -32.004 -90)
		(property "Reference" "PG6"
			(at 0 0 270)
			(layer "F.SilkS")
			(hide yes)
			(effects
				(font
					(size 1.27 1.27)
				)
			)
		)
		(property "Value" "COPPER-CLOSE-GP-U"
			(at 0.0762 -2.8702 270)
			(unlocked yes)
			(layer "F.Fab")
			(hide yes)
			(effects
				(font
					(size 1.016 1.016)
					(thickness 0.1524)
				)
			)
		)
		(property "Device Type" "CON2C-U"
			(at 0.0762 -4.3942 270)
			(unlocked yes)
			(layer "F.Fab")
			(hide yes)
			(effects
				(font
					(size 1.016 1.016)
					(thickness 0.1524)
				)
			)
		)
		(duplicate_pad_numbers_are_jumpers no)
		(fp_rect
			(start -0.9398 0.9652)
			(end 0.9398 -0.9652)
			(stroke
				(width 0)
				(type default)
			)
			(fill no)
			(layer "F.CrtYd")
		)
		(fp_rect
			(start -0.9398 0.9652)
			(end 0.9398 -0.9652)
			(stroke
				(width 0)
				(type default)
			)
			(fill no)
			(layer "F.Fab")
		)
		(pad "1" smd custom
			(at 0 -0.5334 270)
			(size 0.17145 0.17145)
			(layers "F.Cu" "F.Mask" "F.Paste")
			(net "AGND_P3V3_STBY")
			(options
				(clearance outline)
				(anchor circle)
			)
			(primitives
				(gr_poly
					(pts
						(xy -0.127 0.3429) (xy -0.127 0.1651) (xy -0.635 -0.3429) (xy 0.635 -0.3429) (xy 0.127 0.1651)
						(xy 0.127 0.3429)
					)
					(width 0)
					(fill yes)
				)
			)
		)
		(pad "2" smd custom
			(at 0 0.5334 270)
			(size 0.17145 0.17145)
			(layers "F.Cu" "F.Mask" "F.Paste")
			(net "GND")
			(options
				(clearance outline)
				(anchor circle)
			)
			(primitives
				(gr_poly
					(pts
						(xy -0.635 0.3429) (xy -0.127 -0.1651) (xy -0.127 -0.3429) (xy 0.127 -0.3429) (xy 0.127 -0.1651)
						(xy 0.635 0.3429)
					)
					(width 0)
					(fill yes)
				)
			)
		)
	)
	(footprint ""
		(layer "F.Cu")
		(at 38.227 -52.07 -90)
		(property "Reference" "R138"
			(at 0 0 270)
			(layer "F.SilkS")
			(hide yes)
			(effects
				(font
					(size 1.27 1.27)
				)
			)
		)
		(property "Value" "10KR2F-2-GP"
			(at 1.7907 -1.1176 270)
			(unlocked yes)
			(layer "F.Fab")
			(hide yes)
			(effects
				(font
					(size 1.016 1.016)
					(thickness 0.1524)
				)
			)
		)
		(property "Device Type" "R402H16"
			(at 1.7907 -2.6416 270)
			(unlocked yes)
			(layer "F.Fab")
			(hide yes)
			(effects
				(font
					(size 1.016 1.016)
					(thickness 0.1524)
				)
			)
		)
		(duplicate_pad_numbers_are_jumpers no)
		(fp_rect
			(start -0.381 0.8382)
			(end 0.381 -0.8382)
			(stroke
				(width 0)
				(type default)
			)
			(fill no)
			(layer "F.CrtYd")
		)
		(fp_rect
			(start -0.381 0.8382)
			(end 0.381 -0.8382)
			(stroke
				(width 0)
				(type default)
			)
			(fill no)
			(layer "F.Fab")
		)
		(pad "1" smd custom
			(at 0 -0.4318 270)
			(size 0.127 0.127)
			(layers "F.Cu" "F.Mask" "F.Paste")
			(net "GND")
			(options
				(clearance outline)
				(anchor circle)
			)
			(primitives
				(gr_poly
					(pts
						(arc
							(start -0.2032 -0.2794)
							(mid -0.239121 -0.264521)
							(end -0.254 -0.2286)
						)
						(arc
							(start -0.254 0.2286)
							(mid -0.239121 0.264521)
							(end -0.2032 0.2794)
						)
						(arc
							(start 0.2032 0.2794)
							(mid 0.239121 0.264521)
							(end 0.254 0.2286)
						)
						(arc
							(start 0.254 -0.2286)
							(mid 0.239121 -0.264521)
							(end 0.2032 -0.2794)
						)
					)
					(width 0)
					(fill yes)
				)
			)
		)
		(pad "2" smd custom
			(at 0 0.4318 270)
			(size 0.127 0.127)
			(layers "F.Cu" "F.Mask" "F.Paste")
			(net "CLK_14M_CPU")
			(options
				(clearance outline)
				(anchor circle)
			)
			(primitives
				(gr_poly
					(pts
						(arc
							(start -0.2032 -0.2794)
							(mid -0.239121 -0.264521)
							(end -0.254 -0.2286)
						)
						(arc
							(start -0.254 0.2286)
							(mid -0.239121 0.264521)
							(end -0.2032 0.2794)
						)
						(arc
							(start 0.2032 0.2794)
							(mid 0.239121 0.264521)
							(end 0.254 0.2286)
						)
						(arc
							(start 0.254 -0.2286)
							(mid 0.239121 -0.264521)
							(end 0.2032 -0.2794)
						)
					)
					(width 0)
					(fill yes)
				)
			)
		)
	)
	(footprint ""
		(layer "F.Cu")
		(at 52.451 -45.466)
		(property "Reference" "U8"
			(at 0 0 0)
			(layer "F.SilkS")
			(hide yes)
			(effects
				(font
					(size 1.27 1.27)
				)
			)
		)
		(property "Value" "2N7002DW-7F-GP"
			(at -2.3622 -8.2042 0)
			(unlocked yes)
			(layer "F.Fab")
			(hide yes)
			(effects
				(font
					(size 1.016 1.016)
					(thickness 0.1524)
				)
			)
		)
		(property "Device Type" "SOT-363H44"
			(at -2.3622 -10.1092 0)
			(unlocked yes)
			(layer "F.Fab")
			(hide yes)
			(effects
				(font
					(size 1.016 1.016)
					(thickness 0.1524)
				)
			)
		)
		(duplicate_pad_numbers_are_jumpers no)
		(fp_poly
			(pts
				(xy -0.6731 1.4351) (xy -0.9779 1.7399) (xy -0.381 1.7399) (xy -0.3683 1.7399) (xy -0.381 1.7272)
			)
			(stroke
				(width 0)
				(type default)
			)
			(fill yes)
			(layer "F.SilkS")
		)
		(fp_poly
			(pts
				(xy 1.2573 0.8763) (xy 1.2573 -0.8763) (xy 0.9525 -0.8763) (xy 0.9525 -1.4351) (xy -0.9525 -1.4351)
				(xy -0.9525 -0.8763) (xy -1.2573 -0.8763) (xy -1.2573 0.8763) (xy -0.9525 0.8763) (xy -0.9525 1.4351)
				(xy 0.9525 1.4351) (xy 0.9525 0.8763)
			)
			(stroke
				(width 0)
				(type default)
			)
			(fill no)
			(layer "F.CrtYd")
		)
		(fp_poly
			(pts
				(xy 1.2573 0.8763) (xy 1.2573 -0.8763) (xy 0.9525 -0.8763) (xy 0.9525 -1.4351) (xy -0.9525 -1.4351)
				(xy -0.9525 -0.8763) (xy -1.2573 -0.8763) (xy -1.2573 0.8763) (xy -0.9525 0.8763) (xy -0.9525 1.4351)
				(xy 0.9525 1.4351) (xy 0.9525 0.8763)
			)
			(stroke
				(width 0)
				(type default)
			)
			(fill no)
			(layer "F.Fab")
		)
		(pad "1" smd rect
			(at -0.65024 0.8255)
			(size 0.3556 0.9652)
			(layers "F.Cu" "F.Mask" "F.Paste")
			(net "GND")
		)
		(pad "2" smd rect
			(at 0 0.8255)
			(size 0.3556 0.9652)
			(layers "F.Cu" "F.Mask" "F.Paste")
			(net "SW_P3V3_CPU_LV_G2")
		)
		(pad "3" smd rect
			(at 0.65024 0.8255)
			(size 0.3556 0.9652)
			(layers "F.Cu" "F.Mask" "F.Paste")
			(net "SW_P3V3_CPU_EN_LV_D")
		)
		(pad "4" smd rect
			(at 0.65024 -0.8255)
			(size 0.3556 0.9652)
			(layers "F.Cu" "F.Mask" "F.Paste")
			(net "GND")
		)
		(pad "5" smd rect
			(at 0 -0.8255)
			(size 0.3556 0.9652)
			(layers "F.Cu" "F.Mask" "F.Paste")
			(net "SW_P3V3_CPU_LV_G5")
		)
		(pad "6" smd rect
			(at -0.65024 -0.8255)
			(size 0.3556 0.9652)
			(layers "F.Cu" "F.Mask" "F.Paste")
			(net "SW_P3V3_CPU_LV_G5")
		)
	)
	(footprint ""
		(layer "F.Cu")
		(at 21.1328 -67.183)
		(property "Reference" "PR18"
			(at 0 0 0)
			(layer "F.SilkS")
			(hide yes)
			(effects
				(font
					(size 1.27 1.27)
				)
			)
		)
		(property "Value" "10R2F-L-GP"
			(at 1.7907 -1.1176 0)
			(unlocked yes)
			(layer "F.Fab")
			(hide yes)
			(effects
				(font
					(size 1.016 1.016)
					(thickness 0.1524)
				)
			)
		)
		(property "Device Type" "R402H14"
			(at 1.7907 -2.6416 0)
			(unlocked yes)
			(layer "F.Fab")
			(hide yes)
			(effects
				(font
					(size 1.016 1.016)
					(thickness 0.1524)
				)
			)
		)
		(duplicate_pad_numbers_are_jumpers no)
		(fp_rect
			(start -0.381 0.8382)
			(end 0.381 -0.8382)
			(stroke
				(width 0)
				(type default)
			)
			(fill no)
			(layer "F.CrtYd")
		)
		(fp_rect
			(start -0.381 0.8382)
			(end 0.381 -0.8382)
			(stroke
				(width 0)
				(type default)
			)
			(fill no)
			(layer "F.Fab")
		)
		(pad "1" smd custom
			(at 0 -0.4318)
			(size 0.127 0.127)
			(layers "F.Cu" "F.Mask" "F.Paste")
			(net "VR_PVNN_ISUMN_R2")
			(options
				(clearance outline)
				(anchor circle)
			)
			(primitives
				(gr_poly
					(pts
						(arc
							(start -0.2032 -0.2794)
							(mid -0.239121 -0.264521)
							(end -0.254 -0.2286)
						)
						(arc
							(start -0.254 0.2286)
							(mid -0.239121 0.264521)
							(end -0.2032 0.2794)
						)
						(arc
							(start 0.2032 0.2794)
							(mid 0.239121 0.264521)
							(end 0.254 0.2286)
						)
						(arc
							(start 0.254 -0.2286)
							(mid 0.239121 -0.264521)
							(end 0.2032 -0.2794)
						)
					)
					(width 0)
					(fill yes)
				)
			)
		)
		(pad "2" smd custom
			(at 0 0.4318)
			(size 0.127 0.127)
			(layers "F.Cu" "F.Mask" "F.Paste")
			(net "VR_PVNN_ISUMN")
			(options
				(clearance outline)
				(anchor circle)
			)
			(primitives
				(gr_poly
					(pts
						(arc
							(start -0.2032 -0.2794)
							(mid -0.239121 -0.264521)
							(end -0.254 -0.2286)
						)
						(arc
							(start -0.254 0.2286)
							(mid -0.239121 0.264521)
							(end -0.2032 0.2794)
						)
						(arc
							(start 0.2032 0.2794)
							(mid 0.239121 0.264521)
							(end 0.254 0.2286)
						)
						(arc
							(start 0.254 -0.2286)
							(mid 0.239121 -0.264521)
							(end 0.2032 -0.2794)
						)
					)
					(width 0)
					(fill yes)
				)
			)
		)
	)
	(footprint ""
		(layer "F.Cu")
		(at 43.8404 -51.6382 -90)
		(property "Reference" "C53"
			(at 0 0 270)
			(layer "F.SilkS")
			(hide yes)
			(effects
				(font
					(size 1.27 1.27)
				)
			)
		)
		(property "Value" "SC10U6D3V3MX-GP"
			(at -0.0254 -2.0193 270)
			(unlocked yes)
			(layer "F.Fab")
			(hide yes)
			(effects
				(font
					(size 1.016 1.016)
					(thickness 0.1524)
				)
			)
		)
		(property "Device Type" "C603H38"
			(at -0.0254 -3.5433 270)
			(unlocked yes)
			(layer "F.Fab")
			(hide yes)
			(effects
				(font
					(size 1.016 1.016)
					(thickness 0.1524)
				)
			)
		)
		(duplicate_pad_numbers_are_jumpers no)
		(fp_line
			(start -0.4064 0)
			(end 0.4064 0)
			(stroke
				(width 0.2286)
				(type default)
			)
			(layer "F.SilkS")
		)
		(fp_rect
			(start -0.635 1.1811)
			(end 0.635 -1.1811)
			(stroke
				(width 0)
				(type default)
			)
			(fill no)
			(layer "F.CrtYd")
		)
		(fp_rect
			(start -0.635 1.1811)
			(end 0.635 -1.1811)
			(stroke
				(width 0)
				(type default)
			)
			(fill no)
			(layer "F.Fab")
		)
		(pad "1" smd custom
			(at 0 -0.6604 270)
			(size 0.19685 0.19685)
			(layers "F.Cu" "F.Mask" "F.Paste")
			(net "P3V3_CLK_VDD25")
			(options
				(clearance outline)
				(anchor circle)
			)
			(primitives
				(gr_poly
					(pts
						(arc
							(start 0.508 -0.2921)
							(mid 0.478242 -0.363942)
							(end 0.4064 -0.3937)
						)
						(arc
							(start -0.4064 -0.3937)
							(mid -0.478242 -0.363942)
							(end -0.508 -0.2921)
						)
						(arc
							(start -0.508 0.2921)
							(mid -0.478242 0.363942)
							(end -0.4064 0.3937)
						)
						(arc
							(start 0.4064 0.3937)
							(mid 0.478242 0.363942)
							(end 0.508 0.2921)
						)
					)
					(width 0)
					(fill yes)
				)
			)
		)
		(pad "2" smd custom
			(at 0 0.6604 270)
			(size 0.19685 0.19685)
			(layers "F.Cu" "F.Mask" "F.Paste")
			(net "GND")
			(options
				(clearance outline)
				(anchor circle)
			)
			(primitives
				(gr_poly
					(pts
						(arc
							(start 0.508 -0.2921)
							(mid 0.478242 -0.363942)
							(end 0.4064 -0.3937)
						)
						(arc
							(start -0.4064 -0.3937)
							(mid -0.478242 -0.363942)
							(end -0.508 -0.2921)
						)
						(arc
							(start -0.508 0.2921)
							(mid -0.478242 0.363942)
							(end -0.4064 0.3937)
						)
						(arc
							(start 0.4064 0.3937)
							(mid 0.478242 0.363942)
							(end 0.508 0.2921)
						)
					)
					(width 0)
					(fill yes)
				)
			)
		)
	)
	(footprint ""
		(layer "F.Cu")
		(at 109.728 -70.612 90)
		(property "Reference" "R19"
			(at 0 0 90)
			(layer "F.SilkS")
			(hide yes)
			(effects
				(font
					(size 1.27 1.27)
				)
			)
		)
		(property "Value" "1KR2F-3-GP"
			(at 0.064008 -3.993896 90)
			(unlocked yes)
			(layer "F.Fab")
			(hide yes)
			(effects
				(font
					(size 1.016 1.016)
					(thickness 0.1524)
				)
			)
		)
		(property "Device Type" "R402H16"
			(at 0.064008 -5.517896 90)
			(unlocked yes)
			(layer "F.Fab")
			(hide yes)
			(effects
				(font
					(size 1.016 1.016)
					(thickness 0.1524)
				)
			)
		)
		(duplicate_pad_numbers_are_jumpers no)
		(fp_rect
			(start -0.381 0.8382)
			(end 0.381 -0.8382)
			(stroke
				(width 0)
				(type default)
			)
			(fill no)
			(layer "F.CrtYd")
		)
		(fp_rect
			(start -0.381 0.8382)
			(end 0.381 -0.8382)
			(stroke
				(width 0)
				(type default)
			)
			(fill no)
			(layer "F.Fab")
		)
		(pad "1" smd custom
			(at 0 -0.4318 90)
			(size 0.127 0.127)
			(layers "F.Cu" "F.Mask" "F.Paste")
			(net "P3V3_STBY")
			(options
				(clearance outline)
				(anchor circle)
			)
			(primitives
				(gr_poly
					(pts
						(arc
							(start -0.2032 -0.2794)
							(mid -0.239121 -0.264521)
							(end -0.254 -0.2286)
						)
						(arc
							(start -0.254 0.2286)
							(mid -0.239121 0.264521)
							(end -0.2032 0.2794)
						)
						(arc
							(start 0.2032 0.2794)
							(mid 0.239121 0.264521)
							(end 0.254 0.2286)
						)
						(arc
							(start 0.254 -0.2286)
							(mid 0.239121 -0.264521)
							(end 0.2032 -0.2794)
						)
					)
					(width 0)
					(fill yes)
				)
			)
		)
		(pad "2" smd custom
			(at 0 0.4318 90)
			(size 0.127 0.127)
			(layers "F.Cu" "F.Mask" "F.Paste")
			(net "CLK_GEN_OUT_R")
			(options
				(clearance outline)
				(anchor circle)
			)
			(primitives
				(gr_poly
					(pts
						(arc
							(start -0.2032 -0.2794)
							(mid -0.239121 -0.264521)
							(end -0.254 -0.2286)
						)
						(arc
							(start -0.254 0.2286)
							(mid -0.239121 0.264521)
							(end -0.2032 0.2794)
						)
						(arc
							(start 0.2032 0.2794)
							(mid 0.239121 0.264521)
							(end 0.254 0.2286)
						)
						(arc
							(start 0.254 -0.2286)
							(mid 0.239121 -0.264521)
							(end 0.2032 -0.2794)
						)
					)
					(width 0)
					(fill yes)
				)
			)
		)
	)
	(footprint ""
		(layer "F.Cu")
		(at 181.102 -37.338 -90)
		(property "Reference" "R143"
			(at 0 0 270)
			(layer "F.SilkS")
			(hide yes)
			(effects
				(font
					(size 1.27 1.27)
				)
			)
		)
		(property "Value" "56D2R2F-GP"
			(at 0.064008 -3.993896 270)
			(unlocked yes)
			(layer "F.Fab")
			(hide yes)
			(effects
				(font
					(size 1.016 1.016)
					(thickness 0.1524)
				)
			)
		)
		(property "Device Type" "R402H16"
			(at 0.064008 -5.517896 270)
			(unlocked yes)
			(layer "F.Fab")
			(hide yes)
			(effects
				(font
					(size 1.016 1.016)
					(thickness 0.1524)
				)
			)
		)
		(duplicate_pad_numbers_are_jumpers no)
		(fp_rect
			(start -0.381 0.8382)
			(end 0.381 -0.8382)
			(stroke
				(width 0)
				(type default)
			)
			(fill no)
			(layer "F.CrtYd")
		)
		(fp_rect
			(start -0.381 0.8382)
			(end 0.381 -0.8382)
			(stroke
				(width 0)
				(type default)
			)
			(fill no)
			(layer "F.Fab")
		)
		(pad "1" smd custom
			(at 0 -0.4318 270)
			(size 0.127 0.127)
			(layers "F.Cu" "F.Mask" "F.Paste")
			(net "SVID_CPU_CLK")
			(options
				(clearance outline)
				(anchor circle)
			)
			(primitives
				(gr_poly
					(pts
						(arc
							(start -0.2032 -0.2794)
							(mid -0.239121 -0.264521)
							(end -0.254 -0.2286)
						)
						(arc
							(start -0.254 0.2286)
							(mid -0.239121 0.264521)
							(end -0.2032 0.2794)
						)
						(arc
							(start 0.2032 0.2794)
							(mid 0.239121 0.264521)
							(end 0.254 0.2286)
						)
						(arc
							(start 0.254 -0.2286)
							(mid 0.239121 -0.264521)
							(end 0.2032 -0.2794)
						)
					)
					(width 0)
					(fill yes)
				)
			)
		)
		(pad "2" smd custom
			(at 0 0.4318 270)
			(size 0.127 0.127)
			(layers "F.Cu" "F.Mask" "F.Paste")
			(net "P1V0")
			(options
				(clearance outline)
				(anchor circle)
			)
			(primitives
				(gr_poly
					(pts
						(arc
							(start -0.2032 -0.2794)
							(mid -0.239121 -0.264521)
							(end -0.254 -0.2286)
						)
						(arc
							(start -0.254 0.2286)
							(mid -0.239121 0.264521)
							(end -0.2032 0.2794)
						)
						(arc
							(start 0.2032 0.2794)
							(mid 0.239121 0.264521)
							(end 0.254 0.2286)
						)
						(arc
							(start 0.254 -0.2286)
							(mid 0.239121 -0.264521)
							(end 0.2032 -0.2794)
						)
					)
					(width 0)
					(fill yes)
				)
			)
		)
	)
	(footprint ""
		(layer "F.Cu")
		(at 160.274 -48.768 -90)
		(property "Reference" "R205"
			(at 0 0 270)
			(layer "F.SilkS")
			(hide yes)
			(effects
				(font
					(size 1.27 1.27)
				)
			)
		)
		(property "Value" "0R2J-2-GP"
			(at 1.7907 -1.1176 270)
			(unlocked yes)
			(layer "F.Fab")
			(hide yes)
			(effects
				(font
					(size 1.016 1.016)
					(thickness 0.1524)
				)
			)
		)
		(property "Device Type" "R402H16"
			(at 1.7907 -2.6416 270)
			(unlocked yes)
			(layer "F.Fab")
			(hide yes)
			(effects
				(font
					(size 1.016 1.016)
					(thickness 0.1524)
				)
			)
		)
		(duplicate_pad_numbers_are_jumpers no)
		(fp_rect
			(start -0.381 0.8382)
			(end 0.381 -0.8382)
			(stroke
				(width 0)
				(type default)
			)
			(fill no)
			(layer "F.CrtYd")
		)
		(fp_rect
			(start -0.381 0.8382)
			(end 0.381 -0.8382)
			(stroke
				(width 0)
				(type default)
			)
			(fill no)
			(layer "F.Fab")
		)
		(pad "1" smd custom
			(at 0 -0.4318 270)
			(size 0.127 0.127)
			(layers "F.Cu" "F.Mask" "F.Paste")
			(net "XDP_SOC_CPU_TDO")
			(options
				(clearance outline)
				(anchor circle)
			)
			(primitives
				(gr_poly
					(pts
						(arc
							(start -0.2032 -0.2794)
							(mid -0.239121 -0.264521)
							(end -0.254 -0.2286)
						)
						(arc
							(start -0.254 0.2286)
							(mid -0.239121 0.264521)
							(end -0.2032 0.2794)
						)
						(arc
							(start 0.2032 0.2794)
							(mid 0.239121 0.264521)
							(end 0.254 0.2286)
						)
						(arc
							(start 0.254 -0.2286)
							(mid 0.239121 -0.264521)
							(end 0.2032 -0.2794)
						)
					)
					(width 0)
					(fill yes)
				)
			)
		)
		(pad "2" smd custom
			(at 0 0.4318 270)
			(size 0.127 0.127)
			(layers "F.Cu" "F.Mask" "F.Paste")
			(net "XDP_SOC_CPU_TDO_S")
			(options
				(clearance outline)
				(anchor circle)
			)
			(primitives
				(gr_poly
					(pts
						(arc
							(start -0.2032 -0.2794)
							(mid -0.239121 -0.264521)
							(end -0.254 -0.2286)
						)
						(arc
							(start -0.254 0.2286)
							(mid -0.239121 0.264521)
							(end -0.2032 0.2794)
						)
						(arc
							(start 0.2032 0.2794)
							(mid 0.239121 0.264521)
							(end 0.254 0.2286)
						)
						(arc
							(start 0.254 -0.2286)
							(mid 0.239121 -0.264521)
							(end 0.2032 -0.2794)
						)
					)
					(width 0)
					(fill yes)
				)
			)
		)
	)
)
